(kicad_pcb
	(version 20260206)
	(generator "pcbnew")
	(generator_version "10.0")
	(general
		(thickness 1.6)
		(legacy_teardrops no)
	)
	(paper "A4")
	(title_block
		(title "v2-pdb — ms_pdb_v2.brd")
		(comment 1 "Open CloudServer (Microsoft) / footprint 333 of 348 (J15), pads 1-46 of 46")
	)
	(layers
		(0 "F.Cu" signal "TOP")
		(4 "In1.Cu" signal "GND")
		(6 "In2.Cu" signal "IN1")
		(8 "In3.Cu" signal "VCC")
		(10 "In4.Cu" signal "VCC1")
		(12 "In5.Cu" signal "IN2")
		(14 "In6.Cu" signal "GND1")
		(2 "B.Cu" signal "BOTTOM")
		(9 "F.Adhes" user "F.Adhesive")
		(11 "B.Adhes" user "B.Adhesive")
		(13 "F.Paste" user "Package Geometry/Pastemask Top")
		(15 "B.Paste" user "Package Geometry/Pastemask Bottom")
		(5 "F.SilkS" user "Ref Des/Silkscreen Top")
		(7 "B.SilkS" user "Ref Des/Silkscreen Bottom")
		(1 "F.Mask" user "Board Geometry/Soldermask Top")
		(3 "B.Mask" user "Board Geometry/Soldermask Bottom")
		(17 "Dwgs.User" user "User.Drawings")
		(19 "Cmts.User" user "User.Comments")
		(21 "Eco1.User" user "User.Eco1")
		(23 "Eco2.User" user "User.Eco2")
		(25 "Edge.Cuts" user "Board Geometry/Outline")
		(27 "Margin" user)
		(31 "F.CrtYd" user "Package Geometry/Place Bound Top")
		(29 "B.CrtYd" user "Package Geometry/Place Bound Bottom")
		(35 "F.Fab" user "Ref Des/Assembly Top")
		(33 "B.Fab" user "Ref Des/Assembly Bottom")
	)
	(footprint ""
		(layer "B.Cu")
		(at 44.03979 -363.86008 90)
		(property "Reference" "J15"
			(at 6.521196 -4.437888 0)
			(unlocked yes)
			(layer "B.SilkS")
			(effects
				(font
					(size 0.7874 0.5842)
					(thickness 0.1524)
				)
				(justify left mirror)
			)
		)
		(property "Value" ""
			(at 0 0 90)
			(layer "B.Fab")
			(effects
				(font
					(size 1.27 1.27)
				)
				(justify mirror)
			)
		)
		(duplicate_pad_numbers_are_jumpers no)
		(pad "" np_thru_hole circle
			(at -1.35001 -2.54)
			(size 2.5146 2.5146)
			(drill 2.5146)
			(layers "*.Cu" "*.Mask")
			(clearance 0.381)
			(thermal_gap 0.381)
		)
		(pad "" np_thru_hole circle
			(at 0 50.8)
			(size 2.5146 2.5146)
			(drill 2.5146)
			(layers "*.Cu" "*.Mask")
			(clearance 0.381)
			(thermal_gap 0.381)
		)
		(pad "P1" thru_hole rect
			(at 0 0)
			(size 1.1684 1.1684)
			(drill 0.762)
			(layers "*.Cu" "*.Mask")
			(remove_unused_layers no)
			(net "GND")
			(clearance 0.0508)
			(padstack
				(mode front_inner_back)
				(layer "Inner"
					(shape circle)
					(size 1.1684 1.1684)
					(clearance 0.0508)
				)
				(layer "B.Cu"
					(shape rect)
					(size 1.1684 1.1684)
					(thermal_gap 0.0508)
					(clearance 0.0508)
				)
			)
		)
		(pad "P2" thru_hole circle
			(at 0 2.54)
			(size 1.1684 1.1684)
			(drill 0.762)
			(layers "*.Cu" "*.Mask")
			(remove_unused_layers no)
			(net "GND")
			(clearance 0.0508)
			(thermal_gap 0.0508)
		)
		(pad "P3" thru_hole circle
			(at 0 5.08)
			(size 1.1684 1.1684)
			(drill 0.762)
			(layers "*.Cu" "*.Mask")
			(remove_unused_layers no)
			(net "GND")
			(clearance 0.0508)
			(thermal_gap 0.0508)
		)
		(pad "P4" thru_hole circle
			(at 0 7.62)
			(size 1.1684 1.1684)
			(drill 0.762)
			(layers "*.Cu" "*.Mask")
			(remove_unused_layers no)
			(net "GND")
			(clearance 0.0508)
			(thermal_gap 0.0508)
		)
		(pad "P5" thru_hole circle
			(at 0 10.16)
			(size 1.1684 1.1684)
			(drill 0.762)
			(layers "*.Cu" "*.Mask")
			(remove_unused_layers no)
			(net "GND")
			(clearance 0.0508)
			(thermal_gap 0.0508)
		)
		(pad "P6" thru_hole circle
			(at 0 12.7)
			(size 1.1684 1.1684)
			(drill 0.762)
			(layers "*.Cu" "*.Mask")
			(remove_unused_layers no)
			(net "GND")
			(clearance 0.0508)
			(thermal_gap 0.0508)
		)
		(pad "P7" thru_hole circle
			(at 0 15.24)
			(size 1.1684 1.1684)
			(drill 0.762)
			(layers "*.Cu" "*.Mask")
			(remove_unused_layers no)
			(net "GND")
			(clearance 0.0508)
			(thermal_gap 0.0508)
		)
		(pad "P8" thru_hole circle
			(at 0 17.78)
			(size 1.1684 1.1684)
			(drill 0.762)
			(layers "*.Cu" "*.Mask")
			(remove_unused_layers no)
			(net "GND")
			(clearance 0.0508)
			(thermal_gap 0.0508)
		)
		(pad "P9" thru_hole circle
			(at 0 20.32)
			(size 1.1684 1.1684)
			(drill 0.762)
			(layers "*.Cu" "*.Mask")
			(remove_unused_layers no)
			(net "P12V")
			(clearance 0.0508)
			(thermal_gap 0.0508)
		)
		(pad "P10" thru_hole circle
			(at 0 22.86)
			(size 1.1684 1.1684)
			(drill 0.762)
			(layers "*.Cu" "*.Mask")
			(remove_unused_layers no)
			(net "P12V")
			(clearance 0.0508)
			(thermal_gap 0.0508)
		)
		(pad "P11" thru_hole circle
			(at 0 25.4)
			(size 1.1684 1.1684)
			(drill 0.762)
			(layers "*.Cu" "*.Mask")
			(remove_unused_layers no)
			(net "P12V")
			(clearance 0.0508)
			(thermal_gap 0.0508)
		)
		(pad "P12" thru_hole circle
			(at 0 27.94)
			(size 1.1684 1.1684)
			(drill 0.762)
			(layers "*.Cu" "*.Mask")
			(remove_unused_layers no)
			(net "P12V")
			(clearance 0.0508)
			(thermal_gap 0.0508)
		)
		(pad "P13" thru_hole circle
			(at 0 30.48)
			(size 1.1684 1.1684)
			(drill 0.762)
			(layers "*.Cu" "*.Mask")
			(remove_unused_layers no)
			(net "P12V")
			(clearance 0.0508)
			(thermal_gap 0.0508)
		)
		(pad "P14" thru_hole circle
			(at 0 33.02)
			(size 1.1684 1.1684)
			(drill 0.762)
			(layers "*.Cu" "*.Mask")
			(remove_unused_layers no)
			(net "P12V")
			(clearance 0.0508)
			(thermal_gap 0.0508)
		)
		(pad "P15" thru_hole circle
			(at 0 35.56)
			(size 1.1684 1.1684)
			(drill 0.762)
			(layers "*.Cu" "*.Mask")
			(remove_unused_layers no)
			(net "P12V")
			(clearance 0.0508)
			(thermal_gap 0.0508)
		)
		(pad "P16" thru_hole circle
			(at 0 38.1)
			(size 1.1684 1.1684)
			(drill 0.762)
			(layers "*.Cu" "*.Mask")
			(remove_unused_layers no)
			(net "P12V")
			(clearance 0.0508)
			(thermal_gap 0.0508)
		)
		(pad "P17" thru_hole circle
			(at -2.70002 38.1)
			(size 1.1684 1.1684)
			(drill 0.762)
			(layers "*.Cu" "*.Mask")
			(remove_unused_layers no)
			(net "P12V")
			(clearance 0.0508)
			(thermal_gap 0.0508)
		)
		(pad "P18" thru_hole circle
			(at -2.70002 35.56)
			(size 1.1684 1.1684)
			(drill 0.762)
			(layers "*.Cu" "*.Mask")
			(remove_unused_layers no)
			(net "P12V")
			(clearance 0.0508)
			(thermal_gap 0.0508)
		)
		(pad "P19" thru_hole circle
			(at -2.70002 33.02)
			(size 1.1684 1.1684)
			(drill 0.762)
			(layers "*.Cu" "*.Mask")
			(remove_unused_layers no)
			(net "P12V")
			(clearance 0.0508)
			(thermal_gap 0.0508)
		)
		(pad "P20" thru_hole circle
			(at -2.70002 30.48)
			(size 1.1684 1.1684)
			(drill 0.762)
			(layers "*.Cu" "*.Mask")
			(remove_unused_layers no)
			(net "P12V")
			(clearance 0.0508)
			(thermal_gap 0.0508)
		)
		(pad "P21" thru_hole circle
			(at -2.70002 27.94)
			(size 1.1684 1.1684)
			(drill 0.762)
			(layers "*.Cu" "*.Mask")
			(remove_unused_layers no)
			(net "P12V")
			(clearance 0.0508)
			(thermal_gap 0.0508)
		)
		(pad "P22" thru_hole circle
			(at -2.70002 25.4)
			(size 1.1684 1.1684)
			(drill 0.762)
			(layers "*.Cu" "*.Mask")
			(remove_unused_layers no)
			(net "P12V")
			(clearance 0.0508)
			(thermal_gap 0.0508)
		)
		(pad "P23" thru_hole circle
			(at -2.70002 22.86)
			(size 1.1684 1.1684)
			(drill 0.762)
			(layers "*.Cu" "*.Mask")
			(remove_unused_layers no)
			(net "P12V")
			(clearance 0.0508)
			(thermal_gap 0.0508)
		)
		(pad "P24" thru_hole circle
			(at -2.70002 20.32)
			(size 1.1684 1.1684)
			(drill 0.762)
			(layers "*.Cu" "*.Mask")
			(remove_unused_layers no)
			(net "P12V")
			(clearance 0.0508)
			(thermal_gap 0.0508)
		)
		(pad "P25" thru_hole circle
			(at -2.70002 17.78)
			(size 1.1684 1.1684)
			(drill 0.762)
			(layers "*.Cu" "*.Mask")
			(remove_unused_layers no)
			(net "GND")
			(clearance 0.0508)
			(thermal_gap 0.0508)
		)
		(pad "P26" thru_hole circle
			(at -2.70002 15.24)
			(size 1.1684 1.1684)
			(drill 0.762)
			(layers "*.Cu" "*.Mask")
			(remove_unused_layers no)
			(net "GND")
			(clearance 0.0508)
			(thermal_gap 0.0508)
		)
		(pad "P27" thru_hole circle
			(at -2.70002 12.7)
			(size 1.1684 1.1684)
			(drill 0.762)
			(layers "*.Cu" "*.Mask")
			(remove_unused_layers no)
			(net "GND")
			(clearance 0.0508)
			(thermal_gap 0.0508)
		)
		(pad "P28" thru_hole circle
			(at -2.70002 10.16)
			(size 1.1684 1.1684)
			(drill 0.762)
			(layers "*.Cu" "*.Mask")
			(remove_unused_layers no)
			(net "GND")
			(clearance 0.0508)
			(thermal_gap 0.0508)
		)
		(pad "P29" thru_hole circle
			(at -2.70002 7.62)
			(size 1.1684 1.1684)
			(drill 0.762)
			(layers "*.Cu" "*.Mask")
			(remove_unused_layers no)
			(net "GND")
			(clearance 0.0508)
			(thermal_gap 0.0508)
		)
		(pad "P30" thru_hole circle
			(at -2.70002 5.08)
			(size 1.1684 1.1684)
			(drill 0.762)
			(layers "*.Cu" "*.Mask")
			(remove_unused_layers no)
			(net "GND")
			(clearance 0.0508)
			(thermal_gap 0.0508)
		)
		(pad "P31" thru_hole circle
			(at -2.70002 2.54)
			(size 1.1684 1.1684)
			(drill 0.762)
			(layers "*.Cu" "*.Mask")
			(remove_unused_layers no)
			(net "GND")
			(clearance 0.0508)
			(thermal_gap 0.0508)
		)
		(pad "P32" thru_hole circle
			(at -2.70002 0)
			(size 1.1684 1.1684)
			(drill 0.762)
			(layers "*.Cu" "*.Mask")
			(remove_unused_layers no)
			(net "GND")
			(clearance 0.0508)
			(thermal_gap 0.0508)
		)
		(pad "S1" thru_hole circle
			(at 0.55499 41.60012)
			(size 1.1684 1.1684)
			(drill 0.762)
			(layers "*.Cu" "*.Mask")
			(remove_unused_layers no)
			(net "T9_BLAD1_TXD")
			(clearance 0.0508)
			(thermal_gap 0.0508)
		)
		(pad "S2" thru_hole circle
			(at -0.71501 42.87012)
			(size 1.1684 1.1684)
			(drill 0.762)
			(layers "*.Cu" "*.Mask")
			(remove_unused_layers no)
			(net "T9_BLAD1_RXD")
			(clearance 0.0508)
			(thermal_gap 0.0508)
		)
		(pad "S3" thru_hole circle
			(at 0.55499 44.14012)
			(size 1.1684 1.1684)
			(drill 0.762)
			(layers "*.Cu" "*.Mask")
			(remove_unused_layers no)
			(net "T9_BLAD1_EN")
			(clearance 0.0508)
			(thermal_gap 0.0508)
		)
		(pad "S4" thru_hole circle
			(at -0.71501 45.41012)
			(size 1.1684 1.1684)
			(drill 0.762)
			(layers "*.Cu" "*.Mask")
			(remove_unused_layers no)
			(net "B17_PSU_ALERT_N")
			(clearance 0.0508)
			(thermal_gap 0.0508)
		)
		(pad "S5" thru_hole circle
			(at 0.55499 46.68012)
			(size 1.1684 1.1684)
			(drill 0.762)
			(layers "*.Cu" "*.Mask")
			(remove_unused_layers no)
			(net "T9_BLAD2_TXD")
			(clearance 0.0508)
			(thermal_gap 0.0508)
		)
		(pad "S6" thru_hole circle
			(at -0.71501 47.95012)
			(size 1.1684 1.1684)
			(drill 0.762)
			(layers "*.Cu" "*.Mask")
			(remove_unused_layers no)
			(net "T9_BLAD2_RXD")
			(clearance 0.0508)
			(thermal_gap 0.0508)
		)
		(pad "S7" thru_hole circle
			(at -3.25501 47.95012)
			(size 1.1684 1.1684)
			(drill 0.762)
			(layers "*.Cu" "*.Mask")
			(remove_unused_layers no)
			(net "T9_BLAD4_RXD")
			(clearance 0.0508)
			(thermal_gap 0.0508)
		)
		(pad "S8" thru_hole circle
			(at -1.98501 46.68012)
			(size 1.1684 1.1684)
			(drill 0.762)
			(layers "*.Cu" "*.Mask")
			(remove_unused_layers no)
			(net "T9_BLAD4_TXD")
			(clearance 0.0508)
			(thermal_gap 0.0508)
		)
		(pad "S9" thru_hole circle
			(at -3.25501 45.41012)
			(size 1.1684 1.1684)
			(drill 0.762)
			(layers "*.Cu" "*.Mask")
			(remove_unused_layers no)
			(net "B18_PSU_ALERT_N")
			(clearance 0.0508)
			(thermal_gap 0.0508)
		)
		(pad "S10" thru_hole circle
			(at -1.98501 44.14012)
			(size 1.1684 1.1684)
			(drill 0.762)
			(layers "*.Cu" "*.Mask")
			(remove_unused_layers no)
			(net "T9_BLAD3_EN")
			(clearance 0.0508)
			(thermal_gap 0.0508)
		)
		(pad "S11" thru_hole circle
			(at -3.25501 42.87012)
			(size 1.1684 1.1684)
			(drill 0.762)
			(layers "*.Cu" "*.Mask")
			(remove_unused_layers no)
			(net "T9_BLAD3_RXD")
			(clearance 0.0508)
			(thermal_gap 0.0508)
		)
		(pad "S12" thru_hole circle
			(at -1.98501 41.60012)
			(size 1.1684 1.1684)
			(drill 0.762)
			(layers "*.Cu" "*.Mask")
			(remove_unused_layers no)
			(net "T9_BLAD3_TXD")
			(clearance 0.0508)
			(thermal_gap 0.0508)
		)
	)
)
